(kicad_pcb
	(version 20221018)
	(generator pcbnew)
	(general
    (thickness 1.62)
  )
	(paper "A4")
	(title_block
    (title "ECP5 - Datacenter Secure Control Module (DC-SCM)")
    (date "2024-07-01")
    (rev "1.2.1")
		(comment 9 "footprints 30-35 of 506")
	)
	(layers
    (0 "F.Cu" signal)
    (1 "In1.Cu" power)
    (2 "In2.Cu" signal)
    (3 "In3.Cu" power)
    (4 "In4.Cu" power)
    (5 "In5.Cu" signal)
    (6 "In6.Cu" power)
    (31 "B.Cu" signal)
    (32 "B.Adhes" user "B.Adhesive")
    (33 "F.Adhes" user "F.Adhesive")
    (34 "B.Paste" user)
    (35 "F.Paste" user)
    (36 "B.SilkS" user "B.Silkscreen")
    (37 "F.SilkS" user "F.Silkscreen")
    (38 "B.Mask" user)
    (39 "F.Mask" user)
    (40 "Dwgs.User" user "User.Drawings")
    (41 "Cmts.User" user "User.Comments")
    (42 "Eco1.User" user "User.Eco1")
    (43 "Eco2.User" user "User.Eco2")
    (44 "Edge.Cuts" user)
    (45 "Margin" user)
    (46 "B.CrtYd" user "B.Courtyard")
    (47 "F.CrtYd" user "F.Courtyard")
    (48 "B.Fab" user)
    (49 "F.Fab" user)
  )
	(footprint "antmicro-footprints:LED_0603_1608Metric_G" (layer "F.Cu")
    (at 65.5 89.174998 180)
    (descr "LED SMD 0603 Green")
    (tags "LED SMD 0603 Green")
    (property "Author" "Antmicro")
    (property "Color" "Green")
    (property "License" "Apache-2.0")
    (property "MPN" "LG L29K-G2J1-24-Z")
    (property "Manufacturer" "OSRAM")
    (property "Sheetfile" "power-supply.kicad_sch")
    (property "Sheetname" "Power supply")
    (property "ki_description" "LED, Green, SMD, 0603, 20 mA, 1.7 V, 570 nm")
    (property "ki_keywords" "SMT, DIODE, SEMICONDUCTOR, LED")
    (attr smd)
    (fp_text reference "D12" (at 1.8 0.024998 90) (layer "F.SilkS")
        (effects (font (size 0.7 0.7) (thickness 0.127)))
    )
    (fp_text value "LED_G_0603_LG_L29K-G2J1-24-Z" (at 0 1.77) (layer "F.Fab")
        (effects (font (size 1 1) (thickness 0.15)))
    )
    (fp_text user "${REFERENCE}" (at -1.4224 5.999 180) (layer "F.Fab") hide
        (effects (font (size 0.7 0.7) (thickness 0.15)) (justify left bottom))
    )
    (fp_text user "License: Apache-2.0" (at -1.4224 3.599 180) (layer "F.Fab") hide
        (effects (font (size 0.7 0.7) (thickness 0.15)) (justify left bottom))
    )
    (fp_text user "Author: Antmicro" (at -1.4224 4.799 180) (layer "F.Fab") hide
        (effects (font (size 0.7 0.7) (thickness 0.15)) (justify left bottom))
    )
    (fp_line (start -1.18 -0.319) (end -1.18 0.321)
      (stroke (width 0.15) (type solid)) (layer "F.SilkS"))
    (fp_line (start -0.094672 0.001008) (end -0.24 0.001008)
      (stroke (width 0.1) (type solid)) (layer "F.SilkS"))
    (fp_line (start -0.094672 0.001008) (end 0.105328 -0.198992)
      (stroke (width 0.1) (type solid)) (layer "F.SilkS"))
    (fp_line (start -0.094672 0.201008) (end -0.094672 -0.198992)
      (stroke (width 0.1) (type solid)) (layer "F.SilkS"))
    (fp_line (start 0.105328 0.001008) (end 0.24 0.001)
      (stroke (width 0.1) (type solid)) (layer "F.SilkS"))
    (fp_line (start 0.105328 0.201008) (end -0.094672 0.001008)
      (stroke (width 0.1) (type solid)) (layer "F.SilkS"))
    (fp_line (start 0.105328 0.201008) (end 0.105328 -0.198992)
      (stroke (width 0.1) (type solid)) (layer "F.SilkS"))
    (fp_line (start 0.22 -0.35) (end -0.22 -0.35)
      (stroke (width 0.15) (type solid)) (layer "F.SilkS"))
    (fp_line (start 0.22 0.35) (end -0.22 0.35)
      (stroke (width 0.15) (type solid)) (layer "F.SilkS"))
    (fp_rect (start 1.25 0.65) (end -1.25 -0.65)
      (stroke (width 0.05) (type solid)) (fill none) (layer "F.CrtYd"))
    (fp_line (start -0.199 -0.202) (end -0.199 0.1)
      (stroke (width 0.15) (type solid)) (layer "F.Fab"))
    (fp_line (start -0.199 0) (end -0.597 0)
      (stroke (width 0.15) (type solid)) (layer "F.Fab"))
    (fp_line (start -0.199 0.2) (end -0.199 0.1)
      (stroke (width 0.15) (type solid)) (layer "F.Fab"))
    (fp_line (start -0.101 0) (end 0.201 0.2)
      (stroke (width 0.15) (type solid)) (layer "F.Fab"))
    (fp_line (start 0.201 -0.202) (end -0.101 0)
      (stroke (width 0.15) (type solid)) (layer "F.Fab"))
    (fp_line (start 0.201 0) (end 0.201 -0.202)
      (stroke (width 0.15) (type solid)) (layer "F.Fab"))
    (fp_line (start 0.201 0.2) (end 0.201 0)
      (stroke (width 0.15) (type solid)) (layer "F.Fab"))
    (fp_line (start 0.599 0) (end 0.201 0)
      (stroke (width 0.15) (type solid)) (layer "F.Fab"))
    (fp_rect (start 0.848 0.4) (end -0.85 -0.402)
      (stroke (width 0.15) (type solid)) (fill none) (layer "F.Fab"))
    (pad "1" smd roundrect (at -0.7 0) (size 0.8 1) (layers "F.Cu" "F.Paste" "F.Mask") (roundrect_rratio 0.2)
      (net 2 "VCC3V3") (pinfunction "C") (pintype "passive"))
    (pad "2" smd roundrect (at 0.7 0) (size 0.8 1) (layers "F.Cu" "F.Paste" "F.Mask") (roundrect_rratio 0.2)
      (net 346 "Net-(D12-A)") (pinfunction "A") (pintype "passive"))
  )
	(footprint "antmicro-footprints:R_1206_3216Metric" (layer "F.Cu")
    (at 79.25 71.4 180)
    (property "Author" "Antmicro")
    (property "Current" "2A")
    (property "License" "Apache-2.0")
    (property "MPN" "MCMR12X000_PTL")
    (property "Manufacturer" "Multicomp Pro")
    (property "Public" "False")
    (property "Sheetfile" "power-supply.kicad_sch")
    (property "Sheetname" "Power supply")
    (property "Tolerance" "")
    (property "Val" "0R")
    (property "ki_description" "Zero Ohm Resistor, Jumper, 1206 [3216 Metric], Thick Film, 250 mW, 2 A, Surface Mount Device")
    (property "ki_keywords" "1206, SMT, RESISTOR, PASSIVE")
    (attr smd)
    (fp_text reference "R94" (at -2.46 -1.62 180) (layer "F.SilkS")
        (effects (font (size 0.7 0.7) (thickness 0.127)))
    )
    (fp_text value "R_0R_1206" (at 0 2.6) (layer "F.Fab")
        (effects (font (size 1 1) (thickness 0.15)))
    )
    (fp_text user "Author: Antmicro" (at -2.401 4.899 180) (layer "F.Fab") hide
        (effects (font (size 0.7 0.7) (thickness 0.15)) (justify left bottom))
    )
    (fp_text user "License: Apache-2.0" (at -2.401 6.3 180) (layer "F.Fab") hide
        (effects (font (size 0.7 0.7) (thickness 0.15)) (justify left bottom))
    )
    (fp_text user "${REFERENCE}" (at 0 0) (layer "F.Fab")
        (effects (font (size 1 1) (thickness 0.15)))
    )
    (fp_line (start 0.8 -0.899) (end -0.8 -0.899)
      (stroke (width 0.15) (type solid)) (layer "F.SilkS"))
    (fp_line (start 0.8 0.901) (end -0.8 0.901)
      (stroke (width 0.15) (type solid)) (layer "F.SilkS"))
    (fp_rect (start -2.325 -1.15) (end 2.325 1.15)
      (stroke (width 0.05) (type default)) (fill none) (layer "F.CrtYd"))
    (fp_line (start -1.601 -0.802) (end -1.601 0.8)
      (stroke (width 0.15) (type solid)) (layer "F.Fab"))
    (fp_line (start -1.601 -0.802) (end 1.6 -0.802)
      (stroke (width 0.15) (type solid)) (layer "F.Fab"))
    (fp_line (start -1.601 0.8) (end 1.6 0.8)
      (stroke (width 0.15) (type solid)) (layer "F.Fab"))
    (fp_line (start 1.6 -0.802) (end 1.6 0.8)
      (stroke (width 0.15) (type solid)) (layer "F.Fab"))
    (pad "1" smd roundrect (at -1.5 0.001 180) (size 1.15 1.8) (layers "F.Cu" "F.Paste" "F.Mask") (roundrect_rratio 0.25)
      (net 11 "VCC5V0") (pintype "passive"))
    (pad "2" smd roundrect (at 1.5 0.001 180) (size 1.15 1.8) (layers "F.Cu" "F.Paste" "F.Mask") (roundrect_rratio 0.25)
      (net 290 "Net-(C110-Pad2)") (pintype "passive"))
  )
	(footprint "antmicro-footprints:R_0402_1005Metric" (layer "F.Cu")
    (at 86 78.9 180)
    (descr "Resistor SMD 0402")
    (tags "resistor SMD 0402")
    (property "Author" "Antmicro")
    (property "License" "Apache-2.0")
    (property "MPN" "CR0402-FX-1002GLF")
    (property "Manufacturer" "Bourns")
    (property "Public" "False")
    (property "Sheetfile" "power-supply.kicad_sch")
    (property "Sheetname" "Power supply")
    (property "Tolerance" "1%")
    (property "Val" "10k")
    (property "ki_description" "SMD Chip Resistor, 10 kohm, ± 1%, 62.5 mW, 0402 [1005 Metric], Thick Film, General Purpose")
    (property "ki_keywords" "0402, SMT, RESISTOR, PASSIVE")
    (attr smd)
    (fp_text reference "R101" (at 0.72 -1.595) (layer "F.SilkS")
        (effects (font (size 0.7 0.7) (thickness 0.127)))
    )
    (fp_text value "R_10k_0402" (at 0 1.17) (layer "F.Fab")
        (effects (font (size 1 1) (thickness 0.15)))
    )
    (fp_text user "${REFERENCE}" (at 0 0) (layer "F.Fab")
        (effects (font (size 0.25 0.25) (thickness 0.04)))
    )
    (fp_text user "License: Apache-2.0" (at -0.95 5.169) (layer "F.Fab") hide
        (effects (font (size 0.7 0.7) (thickness 0.15)) (justify right bottom))
    )
    (fp_text user "Author: Antmicro" (at -0.95 4.169) (layer "F.Fab") hide
        (effects (font (size 0.7 0.7) (thickness 0.15)) (justify right bottom))
    )
    (fp_rect (start -0.925 -0.47) (end 0.925 0.47)
      (stroke (width 0.05) (type default)) (fill none) (layer "F.CrtYd"))
    (fp_rect (start -0.5 -0.25) (end 0.5 0.25)
      (stroke (width 0.15) (type solid)) (fill none) (layer "F.Fab"))
    (pad "1" smd roundrect (at -0.48 0 180) (size 0.59 0.64) (layers "F.Cu" "F.Paste" "F.Mask") (roundrect_rratio 0.25)
      (net 11 "VCC5V0") (pintype "passive"))
    (pad "2" smd roundrect (at 0.48 0 180) (size 0.59 0.64) (layers "F.Cu" "F.Paste" "F.Mask") (roundrect_rratio 0.25)
      (net 235 "/Power supply/1V2_PG") (pintype "passive"))
  )
	(footprint "antmicro-footprints:LED_0603_1608Metric_G" (layer "F.Cu")
    (at 65.5 87.533332 180)
    (descr "LED SMD 0603 Green")
    (tags "LED SMD 0603 Green")
    (property "Author" "Antmicro")
    (property "Color" "Green")
    (property "License" "Apache-2.0")
    (property "MPN" "LG L29K-G2J1-24-Z")
    (property "Manufacturer" "OSRAM")
    (property "Sheetfile" "power-supply.kicad_sch")
    (property "Sheetname" "Power supply")
    (property "ki_description" "LED, Green, SMD, 0603, 20 mA, 1.7 V, 570 nm")
    (property "ki_keywords" "SMT, DIODE, SEMICONDUCTOR, LED")
    (attr smd)
    (fp_text reference "D13" (at 1.8 0.433332 90) (layer "F.SilkS")
        (effects (font (size 0.7 0.7) (thickness 0.127)))
    )
    (fp_text value "LED_G_0603_LG_L29K-G2J1-24-Z" (at 0 1.77) (layer "F.Fab")
        (effects (font (size 1 1) (thickness 0.15)))
    )
    (fp_text user "Author: Antmicro" (at -1.4224 4.799 180) (layer "F.Fab") hide
        (effects (font (size 0.7 0.7) (thickness 0.15)) (justify left bottom))
    )
    (fp_text user "License: Apache-2.0" (at -1.4224 3.599 180) (layer "F.Fab") hide
        (effects (font (size 0.7 0.7) (thickness 0.15)) (justify left bottom))
    )
    (fp_text user "${REFERENCE}" (at -1.4224 5.999 180) (layer "F.Fab") hide
        (effects (font (size 0.7 0.7) (thickness 0.15)) (justify left bottom))
    )
    (fp_line (start -1.18 -0.319) (end -1.18 0.321)
      (stroke (width 0.15) (type solid)) (layer "F.SilkS"))
    (fp_line (start -0.094672 0.001008) (end -0.24 0.001008)
      (stroke (width 0.1) (type solid)) (layer "F.SilkS"))
    (fp_line (start -0.094672 0.001008) (end 0.105328 -0.198992)
      (stroke (width 0.1) (type solid)) (layer "F.SilkS"))
    (fp_line (start -0.094672 0.201008) (end -0.094672 -0.198992)
      (stroke (width 0.1) (type solid)) (layer "F.SilkS"))
    (fp_line (start 0.105328 0.001008) (end 0.24 0.001)
      (stroke (width 0.1) (type solid)) (layer "F.SilkS"))
    (fp_line (start 0.105328 0.201008) (end -0.094672 0.001008)
      (stroke (width 0.1) (type solid)) (layer "F.SilkS"))
    (fp_line (start 0.105328 0.201008) (end 0.105328 -0.198992)
      (stroke (width 0.1) (type solid)) (layer "F.SilkS"))
    (fp_line (start 0.22 -0.35) (end -0.22 -0.35)
      (stroke (width 0.15) (type solid)) (layer "F.SilkS"))
    (fp_line (start 0.22 0.35) (end -0.22 0.35)
      (stroke (width 0.15) (type solid)) (layer "F.SilkS"))
    (fp_rect (start 1.25 0.65) (end -1.25 -0.65)
      (stroke (width 0.05) (type solid)) (fill none) (layer "F.CrtYd"))
    (fp_line (start -0.199 -0.202) (end -0.199 0.1)
      (stroke (width 0.15) (type solid)) (layer "F.Fab"))
    (fp_line (start -0.199 0) (end -0.597 0)
      (stroke (width 0.15) (type solid)) (layer "F.Fab"))
    (fp_line (start -0.199 0.2) (end -0.199 0.1)
      (stroke (width 0.15) (type solid)) (layer "F.Fab"))
    (fp_line (start -0.101 0) (end 0.201 0.2)
      (stroke (width 0.15) (type solid)) (layer "F.Fab"))
    (fp_line (start 0.201 -0.202) (end -0.101 0)
      (stroke (width 0.15) (type solid)) (layer "F.Fab"))
    (fp_line (start 0.201 0) (end 0.201 -0.202)
      (stroke (width 0.15) (type solid)) (layer "F.Fab"))
    (fp_line (start 0.201 0.2) (end 0.201 0)
      (stroke (width 0.15) (type solid)) (layer "F.Fab"))
    (fp_line (start 0.599 0) (end 0.201 0)
      (stroke (width 0.15) (type solid)) (layer "F.Fab"))
    (fp_rect (start 0.848 0.4) (end -0.85 -0.402)
      (stroke (width 0.15) (type solid)) (fill none) (layer "F.Fab"))
    (pad "1" smd roundrect (at -0.7 0) (size 0.8 1) (layers "F.Cu" "F.Paste" "F.Mask") (roundrect_rratio 0.2)
      (net 2 "VCC3V3") (pinfunction "C") (pintype "passive"))
    (pad "2" smd roundrect (at 0.7 0) (size 0.8 1) (layers "F.Cu" "F.Paste" "F.Mask") (roundrect_rratio 0.2)
      (net 347 "Net-(D13-A)") (pinfunction "A") (pintype "passive"))
  )
	(footprint "antmicro-footprints:TP_SMD_1mm" (layer "F.Cu")
    (at 87.6 78.9 90)
    (property "Author" "Antmicro")
    (property "License" "Apache-2.0")
    (property "MPN" "")
    (property "Manufacturer" "")
    (property "Sheetfile" "power-supply.kicad_sch")
    (property "Sheetname" "Power supply")
    (property "exclude_from_bom" "")
    (property "ki_description" "Test point 1mm SMD")
    (property "ki_keywords" "TESTPOINT")
    (attr exclude_from_pos_files exclude_from_bom)
    (fp_text reference "TP7" (at -2.515 0.68 90) (layer "F.SilkS")
        (effects (font (size 0.7 0.7) (thickness 0.15)) (justify left bottom))
    )
    (fp_text value "TP_1mm_SMD" (at 0 1.4 90) (layer "F.Fab")
        (effects (font (size 0.7 0.7) (thickness 0.15)) (justify left bottom))
    )
    (fp_text user "Author: Antmicro" (at -0.5 4 90) (layer "F.Fab") hide
        (effects (font (size 0.7 0.7) (thickness 0.15)) (justify left bottom))
    )
    (fp_text user "${REFERENCE}" (at -0.5 2.8 90) (layer "F.Fab") hide
        (effects (font (size 0.7 0.7) (thickness 0.15)) (justify left bottom))
    )
    (fp_text user "License: Apache-2.0" (at -0.5 5.2 90) (layer "F.Fab") hide
        (effects (font (size 0.7 0.7) (thickness 0.15)) (justify left bottom))
    )
    (fp_circle (center 0 0) (end 0.6 0)
      (stroke (width 0.05) (type default)) (fill none) (layer "F.CrtYd"))
    (pad "1" smd circle (at 0 0 90) (size 1 1) (layers "F.Cu" "F.Mask")
      (net 354 "Net-(C108-Pad2)") (pinfunction "1") (pintype "passive"))
  )
	(footprint "antmicro-footprints:VSSOP-8_3x3mm_P0.65mm" (layer "F.Cu")
    (at 76.95 76.5 180)
    (property "Author" "Antmicro")
    (property "License" "Apache-2.0")
    (property "MPN" "LM3881MME/NOPB")
    (property "Manufacturer" "Texas Instruments")
    (property "Sheetfile" "power-supply.kicad_sch")
    (property "Sheetname" "Power supply")
    (property "ki_description" "Power Sequencer, 3-Monitors, 2.7V-5.5Vin,VSSOP-8")
    (property "ki_keywords" "SMT, PMIC, IC, POWER, SEQUENCER")
    (attr smd)
    (fp_text reference "U12" (at -4.7 1.485 90) (layer "F.SilkS")
        (effects (font (size 0.7 0.7) (thickness 0.127)) (justify right))
    )
    (fp_text value "LM3881MME_NOPB" (at -0.0254 2.9972) (layer "F.Fab")
        (effects (font (size 1.27 1.27) (thickness 0.15)))
    )
    (fp_text user "${REFERENCE}" (at -0.352 5.972 180) (layer "F.Fab") hide
        (effects (font (size 0.7 0.7) (thickness 0.15)) (justify left bottom))
    )
    (fp_text user "Author: Antmicro" (at -0.352 7.171 180) (layer "F.Fab") hide
        (effects (font (size 0.7 0.7) (thickness 0.15)) (justify left bottom))
    )
    (fp_text user "License: Apache-2.0" (at -0.352 8.371 180) (layer "F.Fab") hide
        (effects (font (size 0.7 0.7) (thickness 0.15)) (justify left bottom))
    )
    (fp_line (start -1.6 -1.625) (end 1.554 -1.625)
      (stroke (width 0.12) (type solid)) (layer "F.SilkS"))
    (fp_line (start -1.496 1.625) (end 1.554 1.625)
      (stroke (width 0.12) (type solid)) (layer "F.SilkS"))
    (fp_circle (center -2.1 -1.438) (end -2.05 -1.438)
      (stroke (width 0.12) (type solid)) (fill solid) (layer "F.SilkS"))
    (fp_rect (start -3 -1.838) (end 3 1.862)
      (stroke (width 0.05) (type solid)) (fill none) (layer "F.CrtYd"))
    (fp_line (start -1.497 -1.502) (end 1.504 -1.502)
      (stroke (width 0.15) (type solid)) (layer "F.Fab"))
    (fp_line (start -1.497 1.5) (end -1.497 -1.502)
      (stroke (width 0.15) (type solid)) (layer "F.Fab"))
    (fp_line (start 1.504 -1.502) (end 1.504 1.5)
      (stroke (width 0.15) (type solid)) (layer "F.Fab"))
    (fp_line (start 1.504 1.5) (end -1.497 1.5)
      (stroke (width 0.15) (type solid)) (layer "F.Fab"))
    (pad "1" smd rect (at -2.096 -0.975 180) (size 1.556504 0.457986) (layers "F.Cu" "F.Paste" "F.Mask")
      (net 11 "VCC5V0") (pinfunction "VCC") (pintype "power_in"))
    (pad "2" smd roundrect (at -2.096 -0.326 180) (size 1.556504 0.457986) (layers "F.Cu" "F.Paste" "F.Mask") (roundrect_rratio 0.5)
      (net 270 "/Power supply/5V0_PG") (pinfunction "EN") (pintype "passive"))
    (pad "3" smd roundrect (at -2.096 0.325 180) (size 1.556504 0.457986) (layers "F.Cu" "F.Paste" "F.Mask") (roundrect_rratio 0.5)
      (net 1 "GND") (pinfunction "GND") (pintype "power_in"))
    (pad "4" smd roundrect (at -2.096 0.974 180) (size 1.556504 0.457986) (layers "F.Cu" "F.Paste" "F.Mask") (roundrect_rratio 0.5)
      (net 1 "GND") (pinfunction "INV") (pintype "input"))
    (pad "5" smd roundrect (at 2.105 0.974 180) (size 1.556504 0.457986) (layers "F.Cu" "F.Paste" "F.Mask") (roundrect_rratio 0.5)
      (net 229 "Net-(U12-TADJ)") (pinfunction "TADJ") (pintype "passive"))
    (pad "6" smd roundrect (at 2.105 0.325 180) (size 1.556504 0.457986) (layers "F.Cu" "F.Paste" "F.Mask") (roundrect_rratio 0.5)
      (net 422 "Net-(U12-FLAG3)") (pinfunction "FLAG3") (pintype "open_collector"))
    (pad "7" smd roundrect (at 2.105 -0.326 180) (size 1.556504 0.457986) (layers "F.Cu" "F.Paste" "F.Mask") (roundrect_rratio 0.5)
      (net 420 "Net-(U12-FLAG2)") (pinfunction "FLAG2") (pintype "open_collector"))
    (pad "8" smd roundrect (at 2.105 -0.975 180) (size 1.556504 0.457986) (layers "F.Cu" "F.Paste" "F.Mask") (roundrect_rratio 0.5)
      (net 419 "Net-(U12-FLAG1)") (pinfunction "FLAG1") (pintype "open_collector"))
  )
)
